# TIMECARD (Time Appliance Project (Time Card)) — schematic netlist excerpt (pin names and nets, part order shuffled) for the footprints in the layout excerpt that follows; sources: Cadence DE-HDL packaged netlist, KiCad conversion of R4006-B0001-02_R01.brd

C12  CAPACITOR  0.1UF 10V 10%  pkg SMC_0402R_H022  page 32 : \1\ = XP5R0V ; \2\ = SG
C38  CAPACITOR  0.1UF 10V 10%  pkg SMC_0402R_H022  page 16 : \1\ = VDD_PCA9546A ; \2\ = SG
TP12  TP_PIONT  pkg TP010CT020B030_PTH  page 25 : \1\ = MUX3_SEL

(kicad_pcb
	(version 20260206)
	(generator "pcbnew")
	(generator_version "10.0")
	(general
		(thickness 1.6)
		(legacy_teardrops no)
	)
	(paper "A4")
	(title_block
		(title "timecard-production-celestica-r4006 — R4006-B0001-02_R01.brd")
		(comment 1 "Time Appliance Project (Time Card) / footprints 568-570 of 1113")
	)
	(layers
		(0 "F.Cu" signal "TOP")
		(4 "In1.Cu" signal "L02_GND1")
		(6 "In2.Cu" signal "L03_SIG1")
		(8 "In3.Cu" signal "L04_GND2")
		(10 "In4.Cu" signal "L05_VCC1")
		(12 "In5.Cu" signal "L06_VCC2")
		(14 "In6.Cu" signal "L07_GND3")
		(16 "In7.Cu" signal "L08_SIG2")
		(18 "In8.Cu" signal "L09_GND4")
		(2 "B.Cu" signal "BOTTOM")
		(9 "F.Adhes" user "F.Adhesive")
		(11 "B.Adhes" user "B.Adhesive")
		(13 "F.Paste" user "Package Geometry/Pastemask Top")
		(15 "B.Paste" user "Package Geometry/Pastemask Bottom")
		(5 "F.SilkS" user "Ref Des/Silkscreen Top")
		(7 "B.SilkS" user "Ref Des/Silkscreen Bottom")
		(1 "F.Mask" user "Board Geometry/Soldermask Top")
		(3 "B.Mask" user "Board Geometry/Soldermask Bottom")
		(17 "Dwgs.User" user "User.Drawings")
		(19 "Cmts.User" user "User.Comments")
		(21 "Eco1.User" user "User.Eco1")
		(23 "Eco2.User" user "User.Eco2")
		(25 "Edge.Cuts" user "Board Geometry/Outline")
		(27 "Margin" user)
		(31 "F.CrtYd" user "Package Geometry/Place Bound Top")
		(29 "B.CrtYd" user "Package Geometry/Place Bound Bottom")
		(35 "F.Fab" user "Ref Des/Assembly Top")
		(33 "B.Fab" user "Ref Des/Assembly Bottom")
	)
	(footprint ""
		(layer "F.Cu")
		(at 121.793 -23.495)
		(property "Reference" "TP12"
			(at -0.2032 -1.67005 0)
			(unlocked yes)
			(layer "F.SilkS")
			(effects
				(font
					(size 0.635 0.4064)
					(thickness 0.1524)
				)
				(justify left)
			)
		)
		(property "Value" ""
			(at 0 0 0)
			(layer "F.Fab")
			(effects
				(font
					(size 1.27 1.27)
				)
			)
		)
		(property "Device Type" "TP_PIONT-TP010CT020B030_PTH-TPA"
			(at -1.341882 0.996696 0)
			(unlocked yes)
			(layer "F.Fab")
			(hide yes)
			(effects
				(font
					(size 0.7874 0.5842)
					(thickness 0.000001)
				)
				(justify left)
			)
		)
		(duplicate_pad_numbers_are_jumpers no)
		(fp_poly
			(pts
				(arc
					(start 0.889 0)
					(mid -0.889 0)
					(end 0.889 0)
				)
			)
			(stroke
				(width 0)
				(type default)
			)
			(fill no)
			(layer "B.CrtYd")
		)
		(fp_poly
			(pts
				(arc
					(start 0.889 0)
					(mid -0.889 0)
					(end 0.889 0)
				)
			)
			(stroke
				(width 0)
				(type default)
			)
			(fill no)
			(layer "F.CrtYd")
		)
		(pad "1" thru_hole circle
			(at 0 0)
			(size 0.508 0.508)
			(drill 0.254)
			(layers "*.Cu" "*.Mask")
			(remove_unused_layers no)
			(net "MUX3_SEL")
			(clearance 0.1016)
			(padstack
				(mode front_inner_back)
				(layer "Inner"
					(shape circle)
					(size 0.508 0.508)
					(clearance 0.1016)
				)
				(layer "B.Cu"
					(shape circle)
					(size 0.762 0.762)
					(clearance -0.0254)
				)
			)
		)
	)
	(footprint ""
		(layer "F.Cu")
		(at 74.0664 -81.4324 180)
		(property "Reference" "C38"
			(at 0.5334 4.50723 0)
			(unlocked yes)
			(layer "F.SilkS")
			(effects
				(font
					(size 0.7874 0.5842)
					(thickness 0.1524)
				)
			)
		)
		(property "Value" "VAL*"
			(at 0.0762 2.067306 180)
			(unlocked yes)
			(layer "F.Fab")
			(hide yes)
			(effects
				(font
					(size 0.7874 0.5842)
					(thickness 0.1524)
				)
			)
		)
		(property "Tolerance" "TOL*"
			(at 0.0762 3.032506 180)
			(unlocked yes)
			(layer "Cmts.User")
			(hide yes)
			(effects
				(font
					(size 0.7874 0.5842)
					(thickness 0.1524)
				)
			)
		)
		(property "User Part Number" "PARTNUM*"
			(at 0.1016 4.023106 180)
			(unlocked yes)
			(layer "Cmts.User")
			(hide yes)
			(effects
				(font
					(size 0.7874 0.5842)
					(thickness 0.1524)
				)
			)
		)
		(property "Device Type" "CAPACITOR-G105-0B104-CK,0.1UF,A"
			(at 0.0508 1.127506 180)
			(unlocked yes)
			(layer "F.Fab")
			(hide yes)
			(effects
				(font
					(size 0.7874 0.5842)
					(thickness 0.1524)
				)
			)
		)
		(duplicate_pad_numbers_are_jumpers no)
		(fp_line
			(start 1.143 0.5588)
			(end 1.143 -0.5588)
			(stroke
				(width 0.1)
				(type default)
			)
			(layer "F.SilkS")
		)
		(fp_line
			(start 1.143 -0.5588)
			(end -1.143 -0.5588)
			(stroke
				(width 0.1)
				(type default)
			)
			(layer "F.SilkS")
		)
		(fp_line
			(start -1.143 0.5588)
			(end 1.143 0.5588)
			(stroke
				(width 0.1)
				(type default)
			)
			(layer "F.SilkS")
		)
		(fp_line
			(start -1.143 -0.5588)
			(end -1.143 0.5588)
			(stroke
				(width 0.1)
				(type default)
			)
			(layer "F.SilkS")
		)
		(fp_rect
			(start 1.143 0.5588)
			(end -1.143 -0.5588)
			(stroke
				(width 0)
				(type default)
			)
			(fill no)
			(layer "F.CrtYd")
		)
		(fp_line
			(start 0.508 0.3048)
			(end 0.508 -0.3048)
			(stroke
				(width 0.1)
				(type default)
			)
			(layer "F.Fab")
		)
		(fp_line
			(start 0.508 -0.3048)
			(end -0.508 -0.3048)
			(stroke
				(width 0.1)
				(type default)
			)
			(layer "F.Fab")
		)
		(fp_line
			(start -0.508 0.3048)
			(end 0.508 0.3048)
			(stroke
				(width 0.1)
				(type default)
			)
			(layer "F.Fab")
		)
		(fp_line
			(start -0.508 -0.3048)
			(end -0.508 0.3048)
			(stroke
				(width 0.1)
				(type default)
			)
			(layer "F.Fab")
		)
		(pad "1" smd rect
			(at -0.5334 0 180)
			(size 0.7112 0.6096)
			(layers "F.Cu" "F.Mask" "F.Paste")
			(net "VDD_PCA9546A")
		)
		(pad "2" smd rect
			(at 0.5334 0 180)
			(size 0.7112 0.6096)
			(layers "F.Cu" "F.Mask" "F.Paste")
			(net "SG")
		)
		(zone
			(layer "F.Cu")
			(hatch none 0.5)
			(connect_pads
				(clearance 0)
			)
			(min_thickness 0.25)
			(keepout
				(tracks allowed)
				(vias not_allowed)
				(pads allowed)
				(copperpour not_allowed)
				(footprints allowed)
			)
			(placement
				(enabled no)
				(sheetname "")
			)
			(fill
				(thermal_gap 0.5)
				(thermal_bridge_width 0.5)
				(island_removal_mode 0)
			)
			(polygon
				(pts
					(xy 73.9902 -81.7372) (xy 73.9902 -81.1276) (xy 74.1426 -81.1276) (xy 74.1426 -81.7372)
				)
			)
		)
	)
	(footprint ""
		(layer "F.Cu")
		(at 55.2704 -98.1964 -90)
		(property "Reference" "C12"
			(at -0.127 -3.59537 90)
			(unlocked yes)
			(layer "F.SilkS")
			(effects
				(font
					(size 0.7874 0.5842)
					(thickness 0.1524)
				)
			)
		)
		(property "Value" "VAL*"
			(at 0.0762 2.067306 270)
			(unlocked yes)
			(layer "F.Fab")
			(hide yes)
			(effects
				(font
					(size 0.7874 0.5842)
					(thickness 0.1524)
				)
			)
		)
		(property "Device Type" "CAPACITOR-G105-0B104-CK,0.1UF,A"
			(at 0.0508 1.127506 270)
			(unlocked yes)
			(layer "F.Fab")
			(hide yes)
			(effects
				(font
					(size 0.7874 0.5842)
					(thickness 0.1524)
				)
			)
		)
		(property "User Part Number" "PARTNUM*"
			(at 0.1016 4.023106 270)
			(unlocked yes)
			(layer "Cmts.User")
			(hide yes)
			(effects
				(font
					(size 0.7874 0.5842)
					(thickness 0.1524)
				)
			)
		)
		(property "Tolerance" "TOL*"
			(at 0.0762 3.032506 270)
			(unlocked yes)
			(layer "Cmts.User")
			(hide yes)
			(effects
				(font
					(size 0.7874 0.5842)
					(thickness 0.1524)
				)
			)
		)
		(duplicate_pad_numbers_are_jumpers no)
		(fp_line
			(start -1.143 0.5588)
			(end 1.143 0.5588)
			(stroke
				(width 0.1)
				(type default)
			)
			(layer "F.SilkS")
		)
		(fp_line
			(start 1.143 0.5588)
			(end 1.143 -0.5588)
			(stroke
				(width 0.1)
				(type default)
			)
			(layer "F.SilkS")
		)
		(fp_line
			(start -1.143 -0.5588)
			(end -1.143 0.5588)
			(stroke
				(width 0.1)
				(type default)
			)
			(layer "F.SilkS")
		)
		(fp_line
			(start 1.143 -0.5588)
			(end -1.143 -0.5588)
			(stroke
				(width 0.1)
				(type default)
			)
			(layer "F.SilkS")
		)
		(fp_rect
			(start -1.143 -0.5588)
			(end 1.143 0.5588)
			(stroke
				(width 0)
				(type default)
			)
			(fill no)
			(layer "F.CrtYd")
		)
		(fp_line
			(start -0.508 0.3048)
			(end 0.508 0.3048)
			(stroke
				(width 0.1)
				(type default)
			)
			(layer "F.Fab")
		)
		(fp_line
			(start 0.508 0.3048)
			(end 0.508 -0.3048)
			(stroke
				(width 0.1)
				(type default)
			)
			(layer "F.Fab")
		)
		(fp_line
			(start -0.508 -0.3048)
			(end -0.508 0.3048)
			(stroke
				(width 0.1)
				(type default)
			)
			(layer "F.Fab")
		)
		(fp_line
			(start 0.508 -0.3048)
			(end -0.508 -0.3048)
			(stroke
				(width 0.1)
				(type default)
			)
			(layer "F.Fab")
		)
		(pad "1" smd rect
			(at -0.5334 0 270)
			(size 0.7112 0.6096)
			(layers "F.Cu" "F.Mask" "F.Paste")
			(net "XP5R0V")
		)
		(pad "2" smd rect
			(at 0.5334 0 270)
			(size 0.7112 0.6096)
			(layers "F.Cu" "F.Mask" "F.Paste")
			(net "SG")
		)
		(zone
			(layer "F.Cu")
			(hatch none 0.5)
			(connect_pads
				(clearance 0)
			)
			(min_thickness 0.25)
			(keepout
				(tracks allowed)
				(vias not_allowed)
				(pads allowed)
				(copperpour not_allowed)
				(footprints allowed)
			)
			(placement
				(enabled no)
				(sheetname "")
			)
			(fill
				(thermal_gap 0.5)
				(thermal_bridge_width 0.5)
				(island_removal_mode 0)
			)
			(polygon
				(pts
					(xy 55.5752 -98.2726) (xy 54.9656 -98.2726) (xy 54.9656 -98.1202) (xy 55.5752 -98.1202)
				)
			)
		)
	)
)
